(kicad_pcb
	(version 20260206)
	(generator "pcbnew")
	(generator_version "10.0")
	(general
		(thickness 1.6)
		(legacy_teardrops no)
	)
	(paper "A4")
	(title_block
		(title "fcb — Lightning_FCB_BRD.brd")
		(comment 1 "Lightning (Wiwynn / Facebook NVMe JBOF) / footprints 210-216 of 495")
	)
	(layers
		(0 "F.Cu" signal "TOP")
		(4 "In1.Cu" signal "L2GND")
		(6 "In2.Cu" signal "L3VCC")
		(2 "B.Cu" signal "BOTTOM")
		(9 "F.Adhes" user "F.Adhesive")
		(11 "B.Adhes" user "B.Adhesive")
		(13 "F.Paste" user "Package Geometry/Pastemask Top")
		(15 "B.Paste" user "Package Geometry/Pastemask Bottom")
		(5 "F.SilkS" user "Ref Des/Silkscreen Top")
		(7 "B.SilkS" user "Ref Des/Silkscreen Bottom")
		(1 "F.Mask" user "Board Geometry/Soldermask Top")
		(3 "B.Mask" user "Board Geometry/Soldermask Bottom")
		(17 "Dwgs.User" user "User.Drawings")
		(19 "Cmts.User" user "User.Comments")
		(21 "Eco1.User" user "User.Eco1")
		(23 "Eco2.User" user "User.Eco2")
		(25 "Edge.Cuts" user "Board Geometry/Outline")
		(27 "Margin" user)
		(31 "F.CrtYd" user "Package Geometry/Place Bound Top")
		(29 "B.CrtYd" user "Package Geometry/Place Bound Bottom")
		(35 "F.Fab" user "Ref Des/Assembly Top")
		(33 "B.Fab" user "Ref Des/Assembly Bottom")
	)
	(footprint ""
		(layer "F.Cu")
		(at 22.71649 -162.262566 180)
		(property "Reference" "R8"
			(at 0 0 180)
			(layer "F.SilkS")
			(hide yes)
			(effects
				(font
					(size 1.27 1.27)
				)
			)
		)
		(property "Value" "0R5J-5-GP"
			(at 0 -8.9535 180)
			(unlocked yes)
			(layer "F.Fab")
			(hide yes)
			(effects
				(font
					(size 1.27 1.016)
					(thickness 0.1524)
				)
			)
		)
		(property "Device Type" "R805H24"
			(at 0 -10.6299 180)
			(unlocked yes)
			(layer "F.Fab")
			(hide yes)
			(effects
				(font
					(size 1.27 1.016)
					(thickness 0.1524)
				)
			)
		)
		(duplicate_pad_numbers_are_jumpers no)
		(fp_line
			(start 0.889 1.7018)
			(end 0.889 -0.508)
			(stroke
				(width 0.1524)
				(type default)
			)
			(layer "F.SilkS")
		)
		(fp_line
			(start 0.889 -1.7018)
			(end 0.889 -0.381)
			(stroke
				(width 0.1524)
				(type default)
			)
			(layer "F.SilkS")
		)
		(fp_line
			(start 0.889 -1.7018)
			(end -0.889 -1.7018)
			(stroke
				(width 0.1524)
				(type default)
			)
			(layer "F.SilkS")
		)
		(fp_line
			(start -0.889 1.7018)
			(end 0.889 1.7018)
			(stroke
				(width 0.1524)
				(type default)
			)
			(layer "F.SilkS")
		)
		(fp_line
			(start -0.889 0.0762)
			(end -0.889 1.7018)
			(stroke
				(width 0.1524)
				(type default)
			)
			(layer "F.SilkS")
		)
		(fp_line
			(start -0.889 -1.7018)
			(end -0.889 0.2794)
			(stroke
				(width 0.1524)
				(type default)
			)
			(layer "F.SilkS")
		)
		(fp_poly
			(pts
				(xy 0.9652 -1.778) (xy 0.9652 1.778) (xy -0.9652 1.778) (xy -0.9652 -1.778)
			)
			(stroke
				(width 0)
				(type default)
			)
			(fill no)
			(layer "F.CrtYd")
		)
		(fp_rect
			(start -0.9652 1.778)
			(end 0.9652 -1.778)
			(stroke
				(width 0)
				(type default)
			)
			(fill no)
			(layer "F.Fab")
		)
		(pad "1" smd rect
			(at 0 -0.9652 180)
			(size 1.397 1.143)
			(layers "F.Cu" "F.Mask" "F.Paste")
			(net "NCT7904_GND")
		)
		(pad "2" smd rect
			(at 0 0.9652 180)
			(size 1.397 1.143)
			(layers "F.Cu" "F.Mask" "F.Paste")
			(net "GND")
		)
	)
	(footprint ""
		(layer "F.Cu")
		(at 23.622 -170.434 -90)
		(property "Reference" "R21"
			(at 0 0 270)
			(layer "F.SilkS")
			(hide yes)
			(effects
				(font
					(size 1.27 1.27)
				)
			)
		)
		(property "Value" "100KR2F-L1-GP"
			(at 0.064008 -3.993896 270)
			(unlocked yes)
			(layer "F.Fab")
			(hide yes)
			(effects
				(font
					(size 1.016 1.016)
					(thickness 0.1524)
				)
			)
		)
		(property "Device Type" "R402H16"
			(at 0.064008 -5.517896 270)
			(unlocked yes)
			(layer "F.Fab")
			(hide yes)
			(effects
				(font
					(size 1.016 1.016)
					(thickness 0.1524)
				)
			)
		)
		(duplicate_pad_numbers_are_jumpers no)
		(fp_line
			(start -0.508 -0.9398)
			(end -0.508 0.9398)
			(stroke
				(width 0.1524)
				(type default)
			)
			(layer "F.SilkS")
		)
		(fp_line
			(start 0.508 -0.9398)
			(end -0.508 -0.9398)
			(stroke
				(width 0.1524)
				(type default)
			)
			(layer "F.SilkS")
		)
		(fp_rect
			(start -0.508 0.9398)
			(end 0.508 -0.9398)
			(stroke
				(width 0)
				(type default)
			)
			(fill no)
			(layer "F.CrtYd")
		)
		(fp_rect
			(start -0.508 0.9398)
			(end 0.508 -0.9398)
			(stroke
				(width 0)
				(type default)
			)
			(fill no)
			(layer "F.Fab")
		)
		(pad "1" smd custom
			(at 0 -0.4445 270)
			(size 0.1397 0.1397)
			(layers "F.Cu" "F.Mask" "F.Paste")
			(net "PWM_EXP_2B")
			(options
				(clearance outline)
				(anchor circle)
			)
			(primitives
				(gr_poly
					(pts
						(arc
							(start -0.1778 -0.2794)
							(mid -0.249642 -0.249642)
							(end -0.2794 -0.1778)
						)
						(arc
							(start -0.2794 0.1778)
							(mid -0.249642 0.249642)
							(end -0.1778 0.2794)
						)
						(arc
							(start 0.1778 0.2794)
							(mid 0.249642 0.249642)
							(end 0.2794 0.1778)
						)
						(arc
							(start 0.2794 -0.1778)
							(mid 0.249642 -0.249642)
							(end 0.1778 -0.2794)
						)
					)
					(width 0)
					(fill yes)
				)
			)
		)
		(pad "2" smd custom
			(at 0 0.4445 270)
			(size 0.1397 0.1397)
			(layers "F.Cu" "F.Mask" "F.Paste")
			(net "GND")
			(options
				(clearance outline)
				(anchor circle)
			)
			(primitives
				(gr_poly
					(pts
						(arc
							(start -0.1778 -0.2794)
							(mid -0.249642 -0.249642)
							(end -0.2794 -0.1778)
						)
						(arc
							(start -0.2794 0.1778)
							(mid -0.249642 0.249642)
							(end -0.1778 0.2794)
						)
						(arc
							(start 0.1778 0.2794)
							(mid 0.249642 0.249642)
							(end 0.2794 0.1778)
						)
						(arc
							(start 0.2794 -0.1778)
							(mid 0.249642 -0.249642)
							(end 0.1778 -0.2794)
						)
					)
					(width 0)
					(fill yes)
				)
			)
		)
	)
	(footprint ""
		(layer "F.Cu")
		(at 6.604 -280.924 -90)
		(property "Reference" "R37"
			(at 0 0 270)
			(layer "F.SilkS")
			(hide yes)
			(effects
				(font
					(size 1.27 1.27)
				)
			)
		)
		(property "Value" "33R2F-3-GP"
			(at 0.064008 -3.993896 270)
			(unlocked yes)
			(layer "F.Fab")
			(hide yes)
			(effects
				(font
					(size 1.016 1.016)
					(thickness 0.1524)
				)
			)
		)
		(property "Device Type" "R402H16"
			(at 0.064008 -5.517896 270)
			(unlocked yes)
			(layer "F.Fab")
			(hide yes)
			(effects
				(font
					(size 1.016 1.016)
					(thickness 0.1524)
				)
			)
		)
		(duplicate_pad_numbers_are_jumpers no)
		(fp_line
			(start -0.508 -0.9398)
			(end -0.508 0.9398)
			(stroke
				(width 0.1524)
				(type default)
			)
			(layer "F.SilkS")
		)
		(fp_line
			(start 0.508 -0.9398)
			(end -0.508 -0.9398)
			(stroke
				(width 0.1524)
				(type default)
			)
			(layer "F.SilkS")
		)
		(fp_rect
			(start -0.508 0.9398)
			(end 0.508 -0.9398)
			(stroke
				(width 0)
				(type default)
			)
			(fill no)
			(layer "F.CrtYd")
		)
		(fp_rect
			(start -0.508 0.9398)
			(end 0.508 -0.9398)
			(stroke
				(width 0)
				(type default)
			)
			(fill no)
			(layer "F.Fab")
		)
		(pad "1" smd custom
			(at 0 -0.4445 270)
			(size 0.1397 0.1397)
			(layers "F.Cu" "F.Mask" "F.Paste")
			(net "P3V3")
			(options
				(clearance outline)
				(anchor circle)
			)
			(primitives
				(gr_poly
					(pts
						(arc
							(start -0.1778 -0.2794)
							(mid -0.249642 -0.249642)
							(end -0.2794 -0.1778)
						)
						(arc
							(start -0.2794 0.1778)
							(mid -0.249642 0.249642)
							(end -0.1778 0.2794)
						)
						(arc
							(start 0.1778 0.2794)
							(mid 0.249642 0.249642)
							(end 0.2794 0.1778)
						)
						(arc
							(start 0.2794 -0.1778)
							(mid 0.249642 -0.249642)
							(end 0.1778 -0.2794)
						)
					)
					(width 0)
					(fill yes)
				)
			)
		)
		(pad "2" smd custom
			(at 0 0.4445 270)
			(size 0.1397 0.1397)
			(layers "F.Cu" "F.Mask" "F.Paste")
			(net "LED_DR_LED2_BLUE")
			(options
				(clearance outline)
				(anchor circle)
			)
			(primitives
				(gr_poly
					(pts
						(arc
							(start -0.1778 -0.2794)
							(mid -0.249642 -0.249642)
							(end -0.2794 -0.1778)
						)
						(arc
							(start -0.2794 0.1778)
							(mid -0.249642 0.249642)
							(end -0.1778 0.2794)
						)
						(arc
							(start 0.1778 0.2794)
							(mid 0.249642 0.249642)
							(end 0.2794 0.1778)
						)
						(arc
							(start 0.2794 -0.1778)
							(mid 0.249642 -0.249642)
							(end 0.1778 -0.2794)
						)
					)
					(width 0)
					(fill yes)
				)
			)
		)
	)
	(footprint ""
		(layer "F.Cu")
		(at 7.949946 -88.535002 -90)
		(property "Reference" "LED5"
			(at 0 0 270)
			(layer "F.SilkS")
			(hide yes)
			(effects
				(font
					(size 1.27 1.27)
				)
			)
		)
		(property "Value" "LED-RB-6-GP"
			(at -4.6736 3.8354 270)
			(unlocked yes)
			(layer "F.Fab")
			(hide yes)
			(effects
				(font
					(size 1.016 1.016)
					(thickness 0.1524)
				)
			)
		)
		(property "Device Type" "LED-100-3P-067106H325"
			(at -4.6736 2.3114 270)
			(unlocked yes)
			(layer "F.Fab")
			(hide yes)
			(effects
				(font
					(size 1.016 1.016)
					(thickness 0.1524)
				)
			)
		)
		(duplicate_pad_numbers_are_jumpers no)
		(fp_line
			(start -1.7526 10.414)
			(end -1.7526 6.6548)
			(stroke
				(width 0.1524)
				(type default)
			)
			(layer "F.SilkS")
		)
		(fp_line
			(start 1.7526 10.414)
			(end -1.7526 10.414)
			(stroke
				(width 0.1524)
				(type default)
			)
			(layer "F.SilkS")
		)
		(fp_line
			(start -3.6068 6.6548)
			(end -3.6068 -0.889)
			(stroke
				(width 0.1524)
				(type default)
			)
			(layer "F.SilkS")
		)
		(fp_line
			(start -1.7526 6.6548)
			(end -3.6068 6.6548)
			(stroke
				(width 0.1524)
				(type default)
			)
			(layer "F.SilkS")
		)
		(fp_line
			(start 1.7526 6.6548)
			(end 1.7526 10.414)
			(stroke
				(width 0.1524)
				(type default)
			)
			(layer "F.SilkS")
		)
		(fp_line
			(start 3.6068 6.6548)
			(end 1.7526 6.6548)
			(stroke
				(width 0.1524)
				(type default)
			)
			(layer "F.SilkS")
		)
		(fp_line
			(start -3.6068 -0.889)
			(end 3.6068 -0.889)
			(stroke
				(width 0.1524)
				(type default)
			)
			(layer "F.SilkS")
		)
		(fp_line
			(start 3.6068 -0.889)
			(end 3.6068 6.6548)
			(stroke
				(width 0.1524)
				(type default)
			)
			(layer "F.SilkS")
		)
		(fp_circle
			(center -2.54 0)
			(end -2.54 -0.9906)
			(stroke
				(width 0.3048)
				(type default)
			)
			(fill no)
			(layer "F.SilkS")
		)
		(fp_circle
			(center 0 0)
			(end 0 -0.9906)
			(stroke
				(width 0.3048)
				(type default)
			)
			(fill no)
			(layer "F.SilkS")
		)
		(fp_circle
			(center 2.54 0)
			(end 2.54 -0.9906)
			(stroke
				(width 0.3048)
				(type default)
			)
			(fill no)
			(layer "F.SilkS")
		)
		(fp_poly
			(pts
				(xy -1.4986 10.1473) (xy -1.4986 6.4008) (xy -3.3528 6.4008) (xy -3.3528 -0.3937) (xy 3.3528 -0.3937)
				(xy 3.3528 6.4008) (xy 1.4986 6.4008) (xy 1.4986 10.1473)
			)
			(stroke
				(width 0)
				(type default)
			)
			(fill no)
			(layer "F.CrtYd")
		)
		(fp_poly
			(pts
				(xy -2.0066 10.668) (xy 2.0066 10.668) (xy 2.0066 6.9088) (xy 3.8608 6.9088) (xy 3.8608 2.2098)
				(xy 3.3528 2.2098) (xy 3.3528 6.4008) (xy 1.4986 6.4008) (xy 1.4986 10.1473) (xy -1.4986 10.1473)
				(xy -1.4986 6.4008) (xy -3.3528 6.4008) (xy -3.3528 -0.3937) (xy 3.3528 -0.3937) (xy 3.3528 2.1971)
				(xy 3.8608 2.1971) (xy 3.8608 -1.143) (xy -3.8608 -1.143) (xy -3.8608 6.9088) (xy -2.0066 6.9088)
			)
			(stroke
				(width 0)
				(type default)
			)
			(fill no)
			(layer "F.CrtYd")
		)
		(fp_poly
			(pts
				(xy -2.0066 10.668) (xy -2.0066 6.9088) (xy -3.8608 6.9088) (xy -3.8608 -1.143) (xy 3.8608 -1.143)
				(xy 3.8608 6.9088) (xy 2.0066 6.9088) (xy 2.0066 10.668)
			)
			(stroke
				(width 0)
				(type default)
			)
			(fill no)
			(layer "F.Fab")
		)
		(pad "1" thru_hole circle
			(at 2.54 0 270)
			(size 1.27 1.27)
			(drill 0.889)
			(layers "*.Cu" "*.Mask")
			(remove_unused_layers no)
			(net "LED_DR_LED4_BLUE")
			(clearance 0.1651)
			(thermal_gap 0.1651)
		)
		(pad "2" thru_hole circle
			(at 0 0 270)
			(size 1.27 1.27)
			(drill 0.889)
			(layers "*.Cu" "*.Mask")
			(remove_unused_layers no)
			(net "LED_DR_LED4_K")
			(clearance 0.1651)
			(thermal_gap 0.1651)
		)
		(pad "3" thru_hole circle
			(at -2.54 0 270)
			(size 1.27 1.27)
			(drill 0.889)
			(layers "*.Cu" "*.Mask")
			(remove_unused_layers no)
			(net "LED_DR_LED4")
			(clearance 0.1651)
			(thermal_gap 0.1651)
		)
	)
	(footprint ""
		(layer "F.Cu")
		(at 11.4554 -147.3454)
		(property "Reference" "R70"
			(at 0 0 0)
			(layer "F.SilkS")
			(hide yes)
			(effects
				(font
					(size 1.27 1.27)
				)
			)
		)
		(property "Value" "27KR3F-GP"
			(at -0.0254 -2.5146 0)
			(unlocked yes)
			(layer "F.Fab")
			(hide yes)
			(effects
				(font
					(size 1.016 1.016)
					(thickness 0.1524)
				)
			)
		)
		(property "Device Type" "R603H22"
			(at -0.0254 -4.0386 0)
			(unlocked yes)
			(layer "F.Fab")
			(hide yes)
			(effects
				(font
					(size 1.016 1.016)
					(thickness 0.1524)
				)
			)
		)
		(duplicate_pad_numbers_are_jumpers no)
		(fp_line
			(start -0.4826 0)
			(end -0.2032 0)
			(stroke
				(width 0.2032)
				(type default)
			)
			(layer "F.SilkS")
		)
		(fp_line
			(start 0.2032 0)
			(end 0.4826 0)
			(stroke
				(width 0.2032)
				(type default)
			)
			(layer "F.SilkS")
		)
		(fp_rect
			(start -0.5842 1.3335)
			(end 0.5842 -1.3335)
			(stroke
				(width 0)
				(type default)
			)
			(fill no)
			(layer "F.CrtYd")
		)
		(fp_rect
			(start -0.5842 1.3335)
			(end 0.5842 -1.3335)
			(stroke
				(width 0)
				(type default)
			)
			(fill no)
			(layer "F.Fab")
		)
		(pad "1" smd custom
			(at 0 -0.762)
			(size 0.2159 0.2159)
			(layers "F.Cu" "F.Mask" "F.Paste")
			(net "FAN_TACH10")
			(options
				(clearance outline)
				(anchor circle)
			)
			(primitives
				(gr_poly
					(pts
						(arc
							(start -0.3302 -0.4318)
							(mid -0.402042 -0.402042)
							(end -0.4318 -0.3302)
						)
						(arc
							(start -0.4318 0.3302)
							(mid -0.402042 0.402042)
							(end -0.3302 0.4318)
						)
						(arc
							(start 0.3302 0.4318)
							(mid 0.402042 0.402042)
							(end 0.4318 0.3302)
						)
						(arc
							(start 0.4318 -0.3302)
							(mid 0.402042 -0.402042)
							(end 0.3302 -0.4318)
						)
					)
					(width 0)
					(fill yes)
				)
			)
		)
		(pad "2" smd custom
			(at 0 0.762)
			(size 0.2159 0.2159)
			(layers "F.Cu" "F.Mask" "F.Paste")
			(net "FANIN_10")
			(options
				(clearance outline)
				(anchor circle)
			)
			(primitives
				(gr_poly
					(pts
						(arc
							(start -0.3302 -0.4318)
							(mid -0.402042 -0.402042)
							(end -0.4318 -0.3302)
						)
						(arc
							(start -0.4318 0.3302)
							(mid -0.402042 0.402042)
							(end -0.3302 0.4318)
						)
						(arc
							(start 0.3302 0.4318)
							(mid 0.402042 0.402042)
							(end 0.4318 0.3302)
						)
						(arc
							(start 0.4318 -0.3302)
							(mid 0.402042 -0.402042)
							(end 0.3302 -0.4318)
						)
					)
					(width 0)
					(fill yes)
				)
			)
		)
	)
	(footprint ""
		(layer "F.Cu")
		(at 33.782 -381 180)
		(property "Reference" "PR23"
			(at 0 0 180)
			(layer "F.SilkS")
			(hide yes)
			(effects
				(font
					(size 1.27 1.27)
				)
			)
		)
		(property "Value" "10R2F-L-GP"
			(at 0.064008 -3.993896 180)
			(unlocked yes)
			(layer "F.Fab")
			(hide yes)
			(effects
				(font
					(size 1.016 1.016)
					(thickness 0.1524)
				)
			)
		)
		(property "Device Type" "R402H14"
			(at 0.064008 -5.517896 180)
			(unlocked yes)
			(layer "F.Fab")
			(hide yes)
			(effects
				(font
					(size 1.016 1.016)
					(thickness 0.1524)
				)
			)
		)
		(duplicate_pad_numbers_are_jumpers no)
		(fp_line
			(start 0.508 -0.9398)
			(end -0.508 -0.9398)
			(stroke
				(width 0.1524)
				(type default)
			)
			(layer "F.SilkS")
		)
		(fp_line
			(start -0.508 -0.9398)
			(end -0.508 0.9398)
			(stroke
				(width 0.1524)
				(type default)
			)
			(layer "F.SilkS")
		)
		(fp_rect
			(start -0.508 0.9398)
			(end 0.508 -0.9398)
			(stroke
				(width 0)
				(type default)
			)
			(fill no)
			(layer "F.CrtYd")
		)
		(fp_rect
			(start -0.508 0.9398)
			(end 0.508 -0.9398)
			(stroke
				(width 0)
				(type default)
			)
			(fill no)
			(layer "F.Fab")
		)
		(pad "1" smd custom
			(at 0 -0.4445 180)
			(size 0.1397 0.1397)
			(layers "F.Cu" "F.Mask" "F.Paste")
			(net "ADM1276_SENSE-")
			(options
				(clearance outline)
				(anchor circle)
			)
			(primitives
				(gr_poly
					(pts
						(arc
							(start -0.1778 -0.2794)
							(mid -0.249642 -0.249642)
							(end -0.2794 -0.1778)
						)
						(arc
							(start -0.2794 0.1778)
							(mid -0.249642 0.249642)
							(end -0.1778 0.2794)
						)
						(arc
							(start 0.1778 0.2794)
							(mid 0.249642 0.249642)
							(end 0.2794 0.1778)
						)
						(arc
							(start 0.2794 -0.1778)
							(mid 0.249642 -0.249642)
							(end 0.1778 -0.2794)
						)
					)
					(width 0)
					(fill yes)
				)
			)
		)
		(pad "2" smd custom
			(at 0 0.4445 180)
			(size 0.1397 0.1397)
			(layers "F.Cu" "F.Mask" "F.Paste")
			(net "SENSE-_R3")
			(options
				(clearance outline)
				(anchor circle)
			)
			(primitives
				(gr_poly
					(pts
						(arc
							(start -0.1778 -0.2794)
							(mid -0.249642 -0.249642)
							(end -0.2794 -0.1778)
						)
						(arc
							(start -0.2794 0.1778)
							(mid -0.249642 0.249642)
							(end -0.1778 0.2794)
						)
						(arc
							(start 0.1778 0.2794)
							(mid 0.249642 0.249642)
							(end 0.2794 0.1778)
						)
						(arc
							(start 0.2794 -0.1778)
							(mid 0.249642 -0.249642)
							(end 0.1778 -0.2794)
						)
					)
					(width 0)
					(fill yes)
				)
			)
		)
	)
	(footprint ""
		(layer "F.Cu")
		(at 22.479 -181.7116 90)
		(property "Reference" "D8"
			(at 0 0 90)
			(layer "F.SilkS")
			(hide yes)
			(effects
				(font
					(size 1.27 1.27)
				)
			)
		)
		(property "Value" "BAS16H-GP"
			(at 0 -5.5372 90)
			(unlocked yes)
			(layer "F.Fab")
			(hide yes)
			(effects
				(font
					(size 1.016 1.016)
					(thickness 0.1524)
				)
			)
		)
		(property "Device Type" "SOD123AKH48"
			(at 0 -7.0612 90)
			(unlocked yes)
			(layer "F.Fab")
			(hide yes)
			(effects
				(font
					(size 1.016 1.016)
					(thickness 0.1524)
				)
			)
		)
		(duplicate_pad_numbers_are_jumpers no)
		(fp_line
			(start 1.016 -2.667)
			(end -1.016 -2.667)
			(stroke
				(width 0.1524)
				(type default)
			)
			(layer "F.SilkS")
		)
		(fp_line
			(start -1.016 -2.667)
			(end -1.016 2.667)
			(stroke
				(width 0.1524)
				(type default)
			)
			(layer "F.SilkS")
		)
		(fp_line
			(start 1.016 2.667)
			(end 1.016 -2.667)
			(stroke
				(width 0.1524)
				(type default)
			)
			(layer "F.SilkS")
		)
		(fp_line
			(start -1.016 2.667)
			(end 1.016 2.667)
			(stroke
				(width 0.1524)
				(type default)
			)
			(layer "F.SilkS")
		)
		(fp_line
			(start 0.889 2.921)
			(end -0.889 2.921)
			(stroke
				(width 0.508)
				(type default)
			)
			(layer "F.SilkS")
		)
		(fp_rect
			(start -1.143 3.175)
			(end 1.143 -2.794)
			(stroke
				(width 0)
				(type default)
			)
			(fill no)
			(layer "F.CrtYd")
		)
		(fp_poly
			(pts
				(xy -1.143 -2.794) (xy 1.143 -2.794) (xy 1.143 3.175) (xy -1.143 3.175)
			)
			(stroke
				(width 0)
				(type default)
			)
			(fill no)
			(layer "F.Fab")
		)
		(pad "A" smd rect
			(at 0 -1.6891 90)
			(size 0.889 1.397)
			(layers "F.Cu" "F.Mask" "F.Paste")
			(net "FAN_TACH7")
		)
		(pad "K" smd rect
			(at 0 1.6891 90)
			(size 0.889 1.397)
			(layers "F.Cu" "F.Mask" "F.Paste")
			(net "P12V")
		)
	)
)
